# S9S_MB_2U (Grand Teton) — schematic netlist excerpt (pin names and nets, part order shuffled) for the footprints in the layout excerpt that follows; sources: Cadence DE-HDL packaged netlist, KiCad conversion of 03242023_DA0F0TMBIJ0_F0T_Motherboard_J_brd_V01_OCP.brd

C1248  Q_CAP  47UF 4V 20% X6S  pkg C0805  page 189 : A = P1V05_PCH_AUX ; B = GND
C244  Q_CAP  10UF 6.3V 20% X6S  pkg C0402  page 77 : A = PVCCIN_CPU1 ; B = GND

(kicad_pcb
	(version 20260206)
	(generator "pcbnew")
	(generator_version "10.0")
	(general
		(thickness 1.6)
		(legacy_teardrops no)
	)
	(paper "A4")
	(title_block
		(title "03242023_DA0F0TMBIJ0_F0T_Motherboard_J_brd_V01_OCP.brd")
		(comment 1 "Grand Teton / footprints 1063-1064 of 6105")
	)
	(layers
		(0 "F.Cu" signal "TOP")
		(4 "In1.Cu" signal "GND")
		(6 "In2.Cu" signal "IN1")
		(8 "In3.Cu" signal "GND1")
		(10 "In4.Cu" signal "IN2")
		(12 "In5.Cu" signal "GND2")
		(14 "In6.Cu" signal "IN3")
		(16 "In7.Cu" signal "GND3")
		(18 "In8.Cu" signal "VCC")
		(20 "In9.Cu" signal "VCC1")
		(22 "In10.Cu" signal "GND4")
		(24 "In11.Cu" signal "IN4")
		(26 "In12.Cu" signal "GND5")
		(28 "In13.Cu" signal "IN5")
		(30 "In14.Cu" signal "GND6")
		(32 "In15.Cu" signal "IN6")
		(34 "In16.Cu" signal "GND7")
		(2 "B.Cu" signal "BOTTOM")
		(9 "F.Adhes" user "F.Adhesive")
		(11 "B.Adhes" user "B.Adhesive")
		(13 "F.Paste" user "Package Geometry/Pastemask Top")
		(15 "B.Paste" user "Package Geometry/Pastemask Bottom")
		(5 "F.SilkS" user "Ref Des/Silkscreen Top")
		(7 "B.SilkS" user "Ref Des/Silkscreen Bottom")
		(1 "F.Mask" user "Board Geometry/Soldermask Top")
		(3 "B.Mask" user "Board Geometry/Soldermask Bottom")
		(17 "Dwgs.User" user "User.Drawings")
		(19 "Cmts.User" user "User.Comments")
		(21 "Eco1.User" user "User.Eco1")
		(23 "Eco2.User" user "User.Eco2")
		(25 "Edge.Cuts" user "Board Geometry/Outline")
		(27 "Margin" user)
		(31 "F.CrtYd" user "Package Geometry/Place Bound Top")
		(29 "B.CrtYd" user "Package Geometry/Place Bound Bottom")
		(35 "F.Fab" user "Ref Des/Assembly Top")
		(33 "B.Fab" user "Ref Des/Assembly Bottom")
	)
	(footprint ""
		(layer "F.Cu")
		(at 118.542816 -255.0541 90)
		(property "Reference" "C244"
			(at 0 0 90)
			(layer "F.SilkS")
			(hide yes)
			(effects
				(font
					(size 1.27 1.27)
				)
			)
		)
		(property "Value" ""
			(at 0 0 90)
			(layer "F.Fab")
			(effects
				(font
					(size 1.27 1.27)
				)
			)
		)
		(duplicate_pad_numbers_are_jumpers no)
		(fp_line
			(start 0.7874 -0.4064)
			(end 0.7874 0.4064)
			(stroke
				(width 0.1524)
				(type default)
			)
			(layer "F.SilkS")
		)
		(fp_line
			(start -0.7874 -0.4064)
			(end 0.7874 -0.4064)
			(stroke
				(width 0.1524)
				(type default)
			)
			(layer "F.SilkS")
		)
		(fp_line
			(start 0.7874 0.4064)
			(end -0.7874 0.4064)
			(stroke
				(width 0.1524)
				(type default)
			)
			(layer "F.SilkS")
		)
		(fp_line
			(start -0.7874 0.4064)
			(end -0.7874 -0.4064)
			(stroke
				(width 0.1524)
				(type default)
			)
			(layer "F.SilkS")
		)
		(fp_line
			(start -0.12065 -0.305054)
			(end -0.12065 -0.2794)
			(stroke
				(width 0.1)
				(type default)
			)
			(layer "F.Fab")
		)
		(fp_line
			(start -0.67945 -0.305054)
			(end -0.12065 -0.305054)
			(stroke
				(width 0.1)
				(type default)
			)
			(layer "F.Fab")
		)
		(fp_line
			(start 0.67945 -0.3048)
			(end 0.67945 0.3048)
			(stroke
				(width 0.1)
				(type default)
			)
			(layer "F.Fab")
		)
		(fp_line
			(start 0.12065 -0.3048)
			(end 0.67945 -0.3048)
			(stroke
				(width 0.1)
				(type default)
			)
			(layer "F.Fab")
		)
		(fp_line
			(start 0.12065 -0.2794)
			(end 0.12065 -0.3048)
			(stroke
				(width 0.1)
				(type default)
			)
			(layer "F.Fab")
		)
		(fp_line
			(start -0.12065 -0.2794)
			(end 0.12065 -0.2794)
			(stroke
				(width 0.1)
				(type default)
			)
			(layer "F.Fab")
		)
		(fp_line
			(start 0.120396 0.2794)
			(end -0.12065 0.2794)
			(stroke
				(width 0.1)
				(type default)
			)
			(layer "F.Fab")
		)
		(fp_line
			(start -0.12065 0.2794)
			(end -0.12065 0.3048)
			(stroke
				(width 0.1)
				(type default)
			)
			(layer "F.Fab")
		)
		(fp_line
			(start 0.67945 0.3048)
			(end 0.120396 0.3048)
			(stroke
				(width 0.1)
				(type default)
			)
			(layer "F.Fab")
		)
		(fp_line
			(start 0.120396 0.3048)
			(end 0.120396 0.2794)
			(stroke
				(width 0.1)
				(type default)
			)
			(layer "F.Fab")
		)
		(fp_line
			(start -0.12065 0.3048)
			(end -0.67945 0.3048)
			(stroke
				(width 0.1)
				(type default)
			)
			(layer "F.Fab")
		)
		(fp_line
			(start -0.67945 0.3048)
			(end -0.67945 -0.305054)
			(stroke
				(width 0.1)
				(type default)
			)
			(layer "F.Fab")
		)
		(pad "1" smd circle
			(at -0.40005 0 90)
			(size 0 0)
			(layers "F.Cu" "F.Mask" "F.Paste")
			(net "PVCCIN_CPU1")
		)
		(pad "2" smd circle
			(at 0.40005 0 90)
			(size 0 0)
			(layers "F.Cu" "F.Mask" "F.Paste")
			(net "GND")
		)
	)
	(footprint ""
		(layer "F.Cu")
		(at 302.768 -46.319948)
		(property "Reference" "C1248"
			(at 0 0 0)
			(layer "F.SilkS")
			(hide yes)
			(effects
				(font
					(size 1.27 1.27)
				)
			)
		)
		(property "Value" ""
			(at 0 0 0)
			(layer "F.Fab")
			(effects
				(font
					(size 1.27 1.27)
				)
			)
		)
		(duplicate_pad_numbers_are_jumpers no)
		(fp_line
			(start -1.524 -0.762)
			(end 1.524 -0.762)
			(stroke
				(width 0.1524)
				(type default)
			)
			(layer "F.SilkS")
		)
		(fp_line
			(start -1.524 0.762)
			(end -1.524 -0.762)
			(stroke
				(width 0.1524)
				(type default)
			)
			(layer "F.SilkS")
		)
		(fp_line
			(start 1.524 -0.762)
			(end 1.524 0.762)
			(stroke
				(width 0.1524)
				(type default)
			)
			(layer "F.SilkS")
		)
		(fp_line
			(start 1.524 0.762)
			(end -1.524 0.762)
			(stroke
				(width 0.1524)
				(type default)
			)
			(layer "F.SilkS")
		)
		(fp_line
			(start -1.1049 -0.724916)
			(end -1.1049 0.724916)
			(stroke
				(width 0.1)
				(type default)
			)
			(layer "F.Fab")
		)
		(fp_line
			(start -1.1049 0.724916)
			(end 1.1049 0.724916)
			(stroke
				(width 0.1)
				(type default)
			)
			(layer "F.Fab")
		)
		(fp_line
			(start 1.1049 -0.724916)
			(end -1.1049 -0.724916)
			(stroke
				(width 0.1)
				(type default)
			)
			(layer "F.Fab")
		)
		(fp_line
			(start 1.1049 0.724916)
			(end 1.1049 -0.724916)
			(stroke
				(width 0.1)
				(type default)
			)
			(layer "F.Fab")
		)
		(pad "1" smd rect
			(at -0.889 0 180)
			(size 1.016 1.27)
			(layers "F.Cu" "F.Mask" "F.Paste")
			(net "P1V05_PCH_AUX")
		)
		(pad "2" smd rect
			(at 0.889 0 180)
			(size 1.016 1.27)
			(layers "F.Cu" "F.Mask" "F.Paste")
			(net "GND")
		)
	)
)
